(kicad_pcb
	(version 20260206)
	(generator "pcbnew")
	(generator_version "10.0")
	(general
		(thickness 1.6)
		(legacy_teardrops no)
	)
	(paper "A4")
	(title_block
		(title "01162023_DA0F0TEBIF0_F0T_Expander_BD_F_brd_V02_OCP.brd")
		(comment 1 "Grand Teton / footprints 1967-1968 of 9728")
	)
	(layers
		(0 "F.Cu" signal "TOP")
		(4 "In1.Cu" signal "GND")
		(6 "In2.Cu" signal "VCC")
		(8 "In3.Cu" signal "VCC1")
		(10 "In4.Cu" signal "GND1")
		(12 "In5.Cu" signal "IN1")
		(14 "In6.Cu" signal "GND2")
		(16 "In7.Cu" signal "IN2")
		(18 "In8.Cu" signal "GND3")
		(20 "In9.Cu" signal "IN3")
		(22 "In10.Cu" signal "GND4")
		(24 "In11.Cu" signal "IN4")
		(26 "In12.Cu" signal "GND5")
		(28 "In13.Cu" signal "IN5")
		(30 "In14.Cu" signal "GND6")
		(32 "In15.Cu" signal "IN6")
		(34 "In16.Cu" signal "GND7")
		(2 "B.Cu" signal "BOTTOM")
		(9 "F.Adhes" user "F.Adhesive")
		(11 "B.Adhes" user "B.Adhesive")
		(13 "F.Paste" user "Package Geometry/Pastemask Top")
		(15 "B.Paste" user "Package Geometry/Pastemask Bottom")
		(5 "F.SilkS" user "Ref Des/Silkscreen Top")
		(7 "B.SilkS" user "Ref Des/Silkscreen Bottom")
		(1 "F.Mask" user "Board Geometry/Soldermask Top")
		(3 "B.Mask" user "Board Geometry/Soldermask Bottom")
		(17 "Dwgs.User" user "User.Drawings")
		(19 "Cmts.User" user "User.Comments")
		(21 "Eco1.User" user "User.Eco1")
		(23 "Eco2.User" user "User.Eco2")
		(25 "Edge.Cuts" user "Board Geometry/Outline")
		(27 "Margin" user)
		(31 "F.CrtYd" user "Package Geometry/Place Bound Top")
		(29 "B.CrtYd" user "Package Geometry/Place Bound Bottom")
		(35 "F.Fab" user "Ref Des/Assembly Top")
		(33 "B.Fab" user "Ref Des/Assembly Bottom")
	)
	(footprint ""
		(layer "F.Cu")
		(at 12.964922 -26.785062 180)
		(property "Reference" "J30"
			(at 3.802634 -11.22045 90)
			(unlocked yes)
			(layer "F.SilkS")
			(effects
				(font
					(size 0.7874 0.5842)
					(thickness 0.1524)
				)
			)
		)
		(property "Value" ""
			(at 0 0 180)
			(layer "F.Fab")
			(effects
				(font
					(size 1.27 1.27)
				)
			)
		)
		(duplicate_pad_numbers_are_jumpers no)
		(fp_line
			(start 3.150108 12.115038)
			(end 1.529334 12.115038)
			(stroke
				(width 0.1524)
				(type default)
			)
			(layer "F.SilkS")
		)
		(fp_line
			(start 3.074924 12.014962)
			(end 1.632204 12.014962)
			(stroke
				(width 0.1524)
				(type default)
			)
			(layer "F.SilkS")
		)
		(fp_line
			(start 1.632204 -12.014962)
			(end 3.074924 -12.014962)
			(stroke
				(width 0.1524)
				(type default)
			)
			(layer "F.SilkS")
		)
		(fp_line
			(start 1.529334 -12.115038)
			(end 3.150108 -12.115038)
			(stroke
				(width 0.1524)
				(type default)
			)
			(layer "F.SilkS")
		)
		(fp_line
			(start -1.529334 12.115038)
			(end -3.150108 12.115038)
			(stroke
				(width 0.1524)
				(type default)
			)
			(layer "F.SilkS")
		)
		(fp_line
			(start -1.632204 12.014962)
			(end -3.074924 12.014962)
			(stroke
				(width 0.1524)
				(type default)
			)
			(layer "F.SilkS")
		)
		(fp_line
			(start -3.074924 -12.014962)
			(end -1.632204 -12.014962)
			(stroke
				(width 0.1524)
				(type default)
			)
			(layer "F.SilkS")
		)
		(fp_line
			(start -3.150108 -12.115038)
			(end -1.529334 -12.115038)
			(stroke
				(width 0.1524)
				(type default)
			)
			(layer "F.SilkS")
		)
		(fp_poly
			(pts
				(xy 3.358642 -8.713216) (xy 3.781044 -9.980676) (xy 4.626102 -9.135618)
			)
			(stroke
				(width 0)
				(type default)
			)
			(fill yes)
			(layer "F.SilkS")
		)
		(fp_line
			(start 3.074924 12.014962)
			(end -3.074924 12.014962)
			(stroke
				(width 0.1)
				(type default)
			)
			(layer "F.Fab")
		)
		(fp_line
			(start 3.074924 -12.014962)
			(end 3.074924 12.014962)
			(stroke
				(width 0.1)
				(type default)
			)
			(layer "F.Fab")
		)
		(fp_line
			(start -3.074924 12.014962)
			(end -3.074924 -12.014962)
			(stroke
				(width 0.1)
				(type default)
			)
			(layer "F.Fab")
		)
		(fp_line
			(start -3.074924 -12.014962)
			(end 3.074924 -12.014962)
			(stroke
				(width 0.1)
				(type default)
			)
			(layer "F.Fab")
		)
		(fp_poly
			(pts
				(xy 3.348736 -7.994904) (xy 4.543806 -8.592566) (xy 4.543806 -7.397496)
			)
			(stroke
				(width 0)
				(type default)
			)
			(fill yes)
			(layer "F.Fab")
		)
		(pad "" np_thru_hole circle
			(at -1.75006 -9.815068 90)
			(size 1.1176 1.1176)
			(drill 1.1176)
			(layers "*.Cu" "*.Mask")
			(clearance 0.381)
			(thermal_gap 0.381)
		)
		(pad "" np_thru_hole circle
			(at 0 9.815068 90)
			(size 1.1176 1.1176)
			(drill 1.1176)
			(layers "*.Cu" "*.Mask")
			(clearance 0.381)
			(thermal_gap 0.381)
		)
		(pad "A1" smd rect
			(at 2.29997 -7.994904 90)
			(size 0.381 1.27)
			(layers "F.Cu" "F.Mask" "F.Paste")
			(net "GND")
		)
		(pad "A2" smd rect
			(at 2.29997 -7.394956 90)
			(size 0.381 1.27)
			(layers "F.Cu" "F.Mask" "F.Paste")
			(net "GND")
		)
		(pad "A3" smd rect
			(at 2.29997 -6.795008 90)
			(size 0.381 1.27)
			(layers "F.Cu" "F.Mask" "F.Paste")
			(net "GND")
		)
		(pad "A4" smd rect
			(at 2.29997 -6.19506 90)
			(size 0.381 1.27)
			(layers "F.Cu" "F.Mask" "F.Paste")
			(net "GND")
		)
		(pad "A5" smd rect
			(at 2.29997 -5.595112 90)
			(size 0.381 1.27)
			(layers "F.Cu" "F.Mask" "F.Paste")
			(net "GND")
		)
		(pad "A6" smd rect
			(at 2.29997 -4.99491 90)
			(size 0.381 1.27)
			(layers "F.Cu" "F.Mask" "F.Paste")
			(net "GND")
		)
		(pad "A7" smd rect
			(at 2.29997 -4.394962 90)
			(size 0.381 1.27)
			(layers "F.Cu" "F.Mask" "F.Paste")
			(net "SMB_ISO_SSD0_R_SCL")
		)
		(pad "A8" smd rect
			(at 2.29997 -3.795014 90)
			(size 0.381 1.27)
			(layers "F.Cu" "F.Mask" "F.Paste")
			(net "SMB_ISO_SSD0_R_SDA")
		)
		(pad "A9" smd rect
			(at 2.29997 -3.195066 90)
			(size 0.381 1.27)
			(layers "F.Cu" "F.Mask" "F.Paste")
			(net "RST_SMB_SSD0_ISO_R_N")
		)
		(pad "A10" smd rect
			(at 2.29997 -2.595118 90)
			(size 0.381 1.27)
			(layers "F.Cu" "F.Mask" "F.Paste")
			(net "SSD0_LED_ISO_R_N")
		)
		(pad "A11" smd rect
			(at 2.29997 -1.994916 90)
			(size 0.381 1.27)
			(layers "F.Cu" "F.Mask" "F.Paste")
			(net "PU_CLKREQ0")
		)
		(pad "A12" smd rect
			(at 2.29997 -1.394968 90)
			(size 0.381 1.27)
			(layers "F.Cu" "F.Mask" "F.Paste")
			(net "PRSNT_SSD0_N")
		)
		(pad "A13" smd rect
			(at 2.29997 -0.79502 90)
			(size 0.381 1.27)
			(layers "F.Cu" "F.Mask" "F.Paste")
			(net "GND")
		)
		(pad "A14" smd rect
			(at 2.29997 -0.195072 90)
			(size 0.381 1.27)
			(layers "F.Cu" "F.Mask" "F.Paste")
			(net "Net_8585")
		)
		(pad "A15" smd rect
			(at 2.29997 0.404876 90)
			(size 0.381 1.27)
			(layers "F.Cu" "F.Mask" "F.Paste")
			(net "Net_8584")
		)
		(pad "A16" smd rect
			(at 2.29997 1.005078 90)
			(size 0.381 1.27)
			(layers "F.Cu" "F.Mask" "F.Paste")
			(net "GND")
		)
		(pad "A17" smd rect
			(at 2.29997 1.605026 90)
			(size 0.381 1.27)
			(layers "F.Cu" "F.Mask" "F.Paste")
			(net "P5E_PEX0_STN2_RX_DN<44>")
		)
		(pad "A18" smd rect
			(at 2.29997 2.204974 90)
			(size 0.381 1.27)
			(layers "F.Cu" "F.Mask" "F.Paste")
			(net "P5E_PEX0_STN2_RX_DP<44>")
		)
		(pad "A19" smd rect
			(at 2.29997 2.804922 90)
			(size 0.381 1.27)
			(layers "F.Cu" "F.Mask" "F.Paste")
			(net "GND")
		)
		(pad "A20" smd rect
			(at 2.29997 3.405124 90)
			(size 0.381 1.27)
			(layers "F.Cu" "F.Mask" "F.Paste")
			(net "P5E_PEX0_STN2_RX_DN<45>")
		)
		(pad "A21" smd rect
			(at 2.29997 4.005072 90)
			(size 0.381 1.27)
			(layers "F.Cu" "F.Mask" "F.Paste")
			(net "P5E_PEX0_STN2_RX_DP<45>")
		)
		(pad "A22" smd rect
			(at 2.29997 4.60502 90)
			(size 0.381 1.27)
			(layers "F.Cu" "F.Mask" "F.Paste")
			(net "GND")
		)
		(pad "A23" smd rect
			(at 2.29997 5.204968 90)
			(size 0.381 1.27)
			(layers "F.Cu" "F.Mask" "F.Paste")
			(net "P5E_PEX0_STN2_RX_DN<46>")
		)
		(pad "A24" smd rect
			(at 2.29997 5.804916 90)
			(size 0.381 1.27)
			(layers "F.Cu" "F.Mask" "F.Paste")
			(net "P5E_PEX0_STN2_RX_DP<46>")
		)
		(pad "A25" smd rect
			(at 2.29997 6.405118 90)
			(size 0.381 1.27)
			(layers "F.Cu" "F.Mask" "F.Paste")
			(net "GND")
		)
		(pad "A26" smd rect
			(at 2.29997 7.005066 90)
			(size 0.381 1.27)
			(layers "F.Cu" "F.Mask" "F.Paste")
			(net "P5E_PEX0_STN2_RX_DN<47>")
		)
		(pad "A27" smd rect
			(at 2.29997 7.605014 90)
			(size 0.381 1.27)
			(layers "F.Cu" "F.Mask" "F.Paste")
			(net "P5E_PEX0_STN2_RX_DP<47>")
		)
		(pad "A28" smd rect
			(at 2.29997 8.204962 90)
			(size 0.381 1.27)
			(layers "F.Cu" "F.Mask" "F.Paste")
			(net "GND")
		)
		(pad "B1" smd rect
			(at -2.29997 -7.994904 90)
			(size 0.381 1.27)
			(layers "F.Cu" "F.Mask" "F.Paste")
			(net "P12V_SSD0")
		)
		(pad "B2" smd rect
			(at -2.29997 -7.394956 90)
			(size 0.381 1.27)
			(layers "F.Cu" "F.Mask" "F.Paste")
			(net "P12V_SSD0")
		)
		(pad "B3" smd rect
			(at -2.29997 -6.795008 90)
			(size 0.381 1.27)
			(layers "F.Cu" "F.Mask" "F.Paste")
			(net "P12V_SSD0")
		)
		(pad "B4" smd rect
			(at -2.29997 -6.19506 90)
			(size 0.381 1.27)
			(layers "F.Cu" "F.Mask" "F.Paste")
			(net "P12V_SSD0")
		)
		(pad "B5" smd rect
			(at -2.29997 -5.595112 90)
			(size 0.381 1.27)
			(layers "F.Cu" "F.Mask" "F.Paste")
			(net "P12V_SSD0")
		)
		(pad "B6" smd rect
			(at -2.29997 -4.99491 90)
			(size 0.381 1.27)
			(layers "F.Cu" "F.Mask" "F.Paste")
			(net "P12V_SSD0")
		)
		(pad "B7" smd rect
			(at -2.29997 -4.394962 90)
			(size 0.381 1.27)
			(layers "F.Cu" "F.Mask" "F.Paste")
			(net "Net_8586")
		)
		(pad "B8" smd rect
			(at -2.29997 -3.795014 90)
			(size 0.381 1.27)
			(layers "F.Cu" "F.Mask" "F.Paste")
			(net "Net_8583")
		)
		(pad "B9" smd rect
			(at -2.29997 -3.195066 90)
			(size 0.381 1.27)
			(layers "F.Cu" "F.Mask" "F.Paste")
			(net "DUALPORT_N_SSD0")
		)
		(pad "B10" smd rect
			(at -2.29997 -2.595118 90)
			(size 0.381 1.27)
			(layers "F.Cu" "F.Mask" "F.Paste")
			(net "RST_SSD0_PERST_R_N")
		)
		(pad "B11" smd rect
			(at -2.29997 -1.994916 90)
			(size 0.381 1.27)
			(layers "F.Cu" "F.Mask" "F.Paste")
			(net "P3V3_SSD0")
		)
		(pad "B12" smd rect
			(at -2.29997 -1.394968 90)
			(size 0.381 1.27)
			(layers "F.Cu" "F.Mask" "F.Paste")
			(net "SSD0_PWRDIS_R")
		)
		(pad "B13" smd rect
			(at -2.29997 -0.79502 90)
			(size 0.381 1.27)
			(layers "F.Cu" "F.Mask" "F.Paste")
			(net "GND")
		)
		(pad "B14" smd rect
			(at -2.29997 -0.195072 90)
			(size 0.381 1.27)
			(layers "F.Cu" "F.Mask" "F.Paste")
			(net "CLK_100M_DB800ZL_SSD0_R_DN")
		)
		(pad "B15" smd rect
			(at -2.29997 0.404876 90)
			(size 0.381 1.27)
			(layers "F.Cu" "F.Mask" "F.Paste")
			(net "CLK_100M_DB800ZL_SSD0_R_DP")
		)
		(pad "B16" smd rect
			(at -2.29997 1.005078 90)
			(size 0.381 1.27)
			(layers "F.Cu" "F.Mask" "F.Paste")
			(net "GND")
		)
		(pad "B17" smd rect
			(at -2.29997 1.605026 90)
			(size 0.381 1.27)
			(layers "F.Cu" "F.Mask" "F.Paste")
			(net "P5E_PEX0_STN2_TX_C_DN<44>")
		)
		(pad "B18" smd rect
			(at -2.29997 2.204974 90)
			(size 0.381 1.27)
			(layers "F.Cu" "F.Mask" "F.Paste")
			(net "P5E_PEX0_STN2_TX_C_DP<44>")
		)
		(pad "B19" smd rect
			(at -2.29997 2.804922 90)
			(size 0.381 1.27)
			(layers "F.Cu" "F.Mask" "F.Paste")
			(net "GND")
		)
		(pad "B20" smd rect
			(at -2.29997 3.405124 90)
			(size 0.381 1.27)
			(layers "F.Cu" "F.Mask" "F.Paste")
			(net "P5E_PEX0_STN2_TX_C_DN<45>")
		)
		(pad "B21" smd rect
			(at -2.29997 4.005072 90)
			(size 0.381 1.27)
			(layers "F.Cu" "F.Mask" "F.Paste")
			(net "P5E_PEX0_STN2_TX_C_DP<45>")
		)
		(pad "B22" smd rect
			(at -2.29997 4.60502 90)
			(size 0.381 1.27)
			(layers "F.Cu" "F.Mask" "F.Paste")
			(net "GND")
		)
		(pad "B23" smd rect
			(at -2.29997 5.204968 90)
			(size 0.381 1.27)
			(layers "F.Cu" "F.Mask" "F.Paste")
			(net "P5E_PEX0_STN2_TX_C_DN<46>")
		)
		(pad "B24" smd rect
			(at -2.29997 5.804916 90)
			(size 0.381 1.27)
			(layers "F.Cu" "F.Mask" "F.Paste")
			(net "P5E_PEX0_STN2_TX_C_DP<46>")
		)
		(pad "B25" smd rect
			(at -2.29997 6.405118 90)
			(size 0.381 1.27)
			(layers "F.Cu" "F.Mask" "F.Paste")
			(net "GND")
		)
		(pad "B26" smd rect
			(at -2.29997 7.005066 90)
			(size 0.381 1.27)
			(layers "F.Cu" "F.Mask" "F.Paste")
			(net "P5E_PEX0_STN2_TX_C_DN<47>")
		)
		(pad "B27" smd rect
			(at -2.29997 7.605014 90)
			(size 0.381 1.27)
			(layers "F.Cu" "F.Mask" "F.Paste")
			(net "P5E_PEX0_STN2_TX_C_DP<47>")
		)
		(pad "B28" smd rect
			(at -2.29997 8.204962 90)
			(size 0.381 1.27)
			(layers "F.Cu" "F.Mask" "F.Paste")
			(net "GND")
		)
		(pad "G1" thru_hole oval
			(at 0 -11.364976 90)
			(size 1.6256 3.4798)
			(drill oval 1.1176 2.4638)
			(layers "*.Cu" "*.Mask")
			(remove_unused_layers no)
			(net "GND")
			(clearance 0.127)
			(thermal_gap 0.127)
		)
		(pad "G2" thru_hole oval
			(at 0 11.364976 90)
			(size 1.6256 3.4798)
			(drill oval 1.1176 2.4638)
			(layers "*.Cu" "*.Mask")
			(remove_unused_layers no)
			(net "GND")
			(clearance 0.127)
			(thermal_gap 0.127)
		)
		(zone
			(layer "F.Cu")
			(hatch none 0.5)
			(connect_pads
				(clearance 0)
			)
			(min_thickness 0.25)
			(keepout
				(tracks not_allowed)
				(vias allowed)
				(pads allowed)
				(copperpour not_allowed)
				(footprints allowed)
			)
			(placement
				(enabled no)
				(sheetname "")
			)
			(fill
				(thermal_gap 0.5)
				(thermal_bridge_width 0.5)
				(island_removal_mode 0)
			)
			(polygon
				(pts
					(xy 14.344904 -38.850062) (xy 11.594846 -38.850062) (xy 11.594846 -35.900106) (xy 14.344904 -35.900106)
				)
			)
		)
		(zone
			(layer "F.Cu")
			(hatch none 0.5)
			(connect_pads
				(clearance 0)
			)
			(min_thickness 0.25)
			(keepout
				(tracks not_allowed)
				(vias allowed)
				(pads allowed)
				(copperpour not_allowed)
				(footprints allowed)
			)
			(placement
				(enabled no)
				(sheetname "")
			)
			(fill
				(thermal_gap 0.5)
				(thermal_bridge_width 0.5)
				(island_removal_mode 0)
			)
			(polygon
				(pts
					(xy 15.415006 -17.670018) (xy 11.58494 -17.670018) (xy 11.58494 -14.720062) (xy 15.415006 -14.720062)
				)
			)
		)
		(zone
			(layers "F.Cu" "B.Cu" "In1.Cu" "In2.Cu" "In3.Cu" "In4.Cu" "In5.Cu" "In6.Cu"
				"In7.Cu" "In8.Cu" "In9.Cu" "In10.Cu" "In11.Cu" "In12.Cu" "In13.Cu" "In14.Cu"
				"In15.Cu" "In16.Cu"
			)
			(hatch none 0.5)
			(connect_pads
				(clearance 0)
			)
			(min_thickness 0.25)
			(keepout
				(tracks not_allowed)
				(vias allowed)
				(pads allowed)
				(copperpour not_allowed)
				(footprints allowed)
			)
			(placement
				(enabled no)
				(sheetname "")
			)
			(fill
				(thermal_gap 0.5)
				(thermal_bridge_width 0.5)
				(island_removal_mode 0)
			)
			(polygon
				(pts
					(arc
						(start 13.930122 -36.60013)
						(mid 11.999722 -36.60013)
						(end 13.930122 -36.60013)
					)
				)
			)
		)
		(zone
			(layers "F.Cu" "B.Cu" "In1.Cu" "In2.Cu" "In3.Cu" "In4.Cu" "In5.Cu" "In6.Cu"
				"In7.Cu" "In8.Cu" "In9.Cu" "In10.Cu" "In11.Cu" "In12.Cu" "In13.Cu" "In14.Cu"
				"In15.Cu" "In16.Cu"
			)
			(hatch none 0.5)
			(connect_pads
				(clearance 0)
			)
			(min_thickness 0.25)
			(keepout
				(tracks not_allowed)
				(vias allowed)
				(pads allowed)
				(copperpour not_allowed)
				(footprints allowed)
			)
			(placement
				(enabled no)
				(sheetname "")
			)
			(fill
				(thermal_gap 0.5)
				(thermal_bridge_width 0.5)
				(island_removal_mode 0)
			)
			(polygon
				(pts
					(arc
						(start 15.680182 -16.969994)
						(mid 13.749782 -16.969994)
						(end 15.680182 -16.969994)
					)
				)
			)
		)
	)
	(footprint ""
		(layer "F.Cu")
		(at 312.21934 -146.190208 180)
		(property "Reference" "C434"
			(at 0 0 180)
			(layer "F.SilkS")
			(hide yes)
			(effects
				(font
					(size 1.27 1.27)
				)
			)
		)
		(property "Value" ""
			(at 0 0 180)
			(layer "F.Fab")
			(effects
				(font
					(size 1.27 1.27)
				)
			)
		)
		(duplicate_pad_numbers_are_jumpers no)
		(fp_line
			(start 0.299974 0.150114)
			(end -0.299974 0.150114)
			(stroke
				(width 0.1)
				(type default)
			)
			(layer "F.Fab")
		)
		(fp_line
			(start 0.299974 -0.150114)
			(end 0.299974 0.150114)
			(stroke
				(width 0.1)
				(type default)
			)
			(layer "F.Fab")
		)
		(fp_line
			(start -0.299974 0.150114)
			(end -0.299974 -0.150114)
			(stroke
				(width 0.1)
				(type default)
			)
			(layer "F.Fab")
		)
		(fp_line
			(start -0.299974 -0.150114)
			(end 0.299974 -0.150114)
			(stroke
				(width 0.1)
				(type default)
			)
			(layer "F.Fab")
		)
		(pad "1" smd rect
			(at -0.2667 0 180)
			(size 0.3048 0.381)
			(layers "F.Cu" "F.Mask" "F.Paste")
			(net "P5E_PEX2_STN0_TX_DN<10>")
		)
		(pad "2" smd rect
			(at 0.2667 0 180)
			(size 0.3048 0.381)
			(layers "F.Cu" "F.Mask" "F.Paste")
			(net "P5E_PEX2_STN0_TX_C_DN<10>")
		)
	)
)
